FILE_TYPE = MACRO_DRAWING;
SET COLOR_WIRE YELLOW;
SET COLOR_PROP ORANGE;
SET COLOR_DOT WHITE;
SET COLOR_ARC YELLOW;
SET COLOR_BODY GREEN;
SET COLOR_NOTE PURPLE;
SET PROP_DISPLAY VALUE;
SET PAGE_NUMBER P434;
FORCEADD QUANTA_TITLE_BLOCK_C..1
(0 0);
FORCEPROP 1 LAST CUSTOM_TXT_CDS <NAME_2>
J 0
(-3175 50);
FORCEPROP 1 LAST CUSTOM_TXT_CDS <NAME_1>
J 0
(-3175 175);
FORCEPROP 1 LAST CUSTOM_TXT_CDS <Q_NUMBER>
J 0
(-1403 103);
DISPLAY 1.212766 (-1403 103);
FORCEPROP 1 LAST CUSTOM_TXT_CDS <Q_PROJ>
J 0
(-2382 102);
DISPLAY 1.212766 (-2382 102);
FORCEPROP 1 LAST CUSTOM_TXT_CDS <Q_REV>
J 0
(-184 103);
DISPLAY 1.212766 (-184 103);
FORCEPROP 1 LAST CUSTOM_TXT_CDS <CON_LAST_MODIFIED>
J 0
(-1885 15);
DISPLAY 0.978723 (-1885 15);
FORCEPROP 1 LAST CUSTOM_TXT_CDS <CON_PAGE_NUM> OF <CON_TOTAL_PAGES>
J 0
(-446 18);
DISPLAY 0.978723 (-446 18);
FORCEPROP 1 LAST Q_TITLE RETIMER_CPU0_P3(9)
J 0
(-9366 26);
DISPLAY 2.446809 (-9366 26);
PAINT GREEN (-9366 26);
FORCEPROP 2 LAST CDS_LIB pure_quanta
J 0
(0 0);
DISPLAY INVISIBLE (0 0);
FORCEPROP 1 LAST CDS_LMAN_SYM_OUTLINE -9475,6775,100,-125
J 0
(0 0);
DISPLAY 0.468085 (0 0);
PAINT GREEN (0 0);
DISPLAY INVISIBLE (0 0);
FORCEPROP 2 LAST PAGE_BORDER TRUE
J 0
(-7890 5250);
DISPLAY 0.638298 (-7890 5250);
PAINT PINK (-7890 5250);
DISPLAY INVISIBLE (-7890 5250);
FORCEPROP 2 LAST CDS_XR_PAGE_TITLE CR-314 : @T6G_MB_LIB.T6G(SCH_1):PAGE314
J 0
(-7890 5250);
DISPLAY 0.638298 (-7890 5250);
PAINT PINK (-7890 5250);
DISPLAY INVISIBLE (-7890 5250);
FORCEPROP 2 LAST CUSTOM_TXT_CDS <XR_PAGE_TITLE>
J 0
(-7890 5250);
DISPLAY 0.638298 (-7890 5250);
PAINT PINK (-7890 5250);
DISPLAY INVISIBLE (-7890 5250);
FORCEPROP 1 LAST COMMENT_BODY TRUE
J 0
(12 -13);
DISPLAY 0.978723 (12 -13);
PAINT GREEN (12 -13);
DISPLAY INVISIBLE (12 -13);
FORCEPROP 1 LAST Q_DEPT BU9
J 1
(-3763 49);
DISPLAY 1.957447 (-3763 49);
PAINT GREEN (-3763 49);
DISPLAY INVISIBLE (-3763 49);
FORCEPROP 0 LAST CDS_CON_LAST_MODIFIED Thu Aug 24 10:16:35 2023
J 0
(-1885 15);
DISPLAY INVISIBLE (-1885 15);
QUIT
